# BASEBOARD_FAB2 (Tioga Pass) — schematic netlist excerpt (pin names and nets, part order shuffled) for the footprints in the layout excerpt that follows; sources: Cadence DE-HDL packaged netlist, KiCad conversion of Wiwynn_Tioga_Pass_MB.brd

R1B22  RES  100.0 1% CHIP  pkg 0402  page 161 : A = FAN_TACH2 ; B = FAN_TACH2_CPU1_D2
R9F70  RES  0.0 5% EMPTY  pkg 0402  page 181 : A = SPA_MID_DBG_TX ; B = SPA_MID_DBG_TX_R
CT40  CAP_A  0.1UF 16V 10% X7R  pkg 0402V  page 203 : A = VR_PVCCIN_CPU0_AIREF4 ; B = GND

(kicad_pcb
	(version 20260206)
	(generator "pcbnew")
	(generator_version "10.0")
	(general
		(thickness 1.6)
		(legacy_teardrops no)
	)
	(paper "A4")
	(title_block
		(title "Wiwynn_Tioga_Pass_MB.brd")
		(comment 1 "Tioga Pass / footprints 756-758 of 4770")
	)
	(layers
		(0 "F.Cu" signal "TOP")
		(4 "In1.Cu" signal "L2GND")
		(6 "In2.Cu" signal "L3")
		(8 "In3.Cu" signal "L4GND")
		(10 "In4.Cu" signal "L5")
		(12 "In5.Cu" signal "L6GND")
		(14 "In6.Cu" signal "L7VCC")
		(16 "In7.Cu" signal "L8VCC")
		(18 "In8.Cu" signal "L9GND")
		(20 "In9.Cu" signal "L10")
		(22 "In10.Cu" signal "L11GND")
		(24 "In11.Cu" signal "L12")
		(26 "In12.Cu" signal "L13GND")
		(2 "B.Cu" signal "BOTTOM")
		(9 "F.Adhes" user "F.Adhesive")
		(11 "B.Adhes" user "B.Adhesive")
		(13 "F.Paste" user "Package Geometry/Pastemask Top")
		(15 "B.Paste" user "Package Geometry/Pastemask Bottom")
		(5 "F.SilkS" user "Ref Des/Silkscreen Top")
		(7 "B.SilkS" user "Ref Des/Silkscreen Bottom")
		(1 "F.Mask" user "Board Geometry/Soldermask Top")
		(3 "B.Mask" user "Board Geometry/Soldermask Bottom")
		(17 "Dwgs.User" user "User.Drawings")
		(19 "Cmts.User" user "User.Comments")
		(21 "Eco1.User" user "User.Eco1")
		(23 "Eco2.User" user "User.Eco2")
		(25 "Edge.Cuts" user "Board Geometry/Outline")
		(27 "Margin" user)
		(31 "F.CrtYd" user "Package Geometry/Place Bound Top")
		(29 "B.CrtYd" user "Package Geometry/Place Bound Bottom")
		(35 "F.Fab" user "Ref Des/Assembly Top")
		(33 "B.Fab" user "Ref Des/Assembly Bottom")
	)
	(footprint ""
		(layer "F.Cu")
		(at 194.457828 -78.000352)
		(property "Reference" "CT40"
			(at -0.56007 -5.2324 270)
			(unlocked yes)
			(layer "F.SilkS")
			(effects
				(font
					(size 0.7874 0.5842)
					(thickness 0.1524)
				)
				(justify left)
			)
		)
		(property "Value" ""
			(at 0 0 0)
			(layer "F.Fab")
			(effects
				(font
					(size 1.27 1.27)
				)
			)
		)
		(duplicate_pad_numbers_are_jumpers no)
		(fp_poly
			(pts
				(xy 0.3048 -0.1016) (xy 0.3048 0.9906) (xy -0.3048 0.9906) (xy -0.3048 -0.1016)
			)
			(stroke
				(width 0)
				(type default)
			)
			(fill no)
			(layer "F.CrtYd")
		)
		(fp_line
			(start -0.3048 -0.1016)
			(end -0.3048 0.9906)
			(stroke
				(width 0.1)
				(type default)
			)
			(layer "F.Fab")
		)
		(fp_line
			(start -0.3048 0.9906)
			(end 0.3048 0.9906)
			(stroke
				(width 0.1)
				(type default)
			)
			(layer "F.Fab")
		)
		(fp_line
			(start 0.3048 -0.1016)
			(end -0.3048 -0.1016)
			(stroke
				(width 0.1)
				(type default)
			)
			(layer "F.Fab")
		)
		(fp_line
			(start 0.3048 0.9906)
			(end 0.3048 -0.1016)
			(stroke
				(width 0.1)
				(type default)
			)
			(layer "F.Fab")
		)
		(pad "1" smd rect
			(at 0 0)
			(size 0.508 0.508)
			(layers "F.Cu" "F.Mask" "F.Paste")
			(net "VR_PVCCIN_CPU0_AIREF4")
		)
		(pad "2" smd rect
			(at 0 0.889)
			(size 0.508 0.508)
			(layers "F.Cu" "F.Mask" "F.Paste")
			(net "GND")
		)
		(zone
			(layer "F.Cu")
			(hatch none 0.5)
			(connect_pads
				(clearance 0)
			)
			(min_thickness 0.25)
			(keepout
				(tracks allowed)
				(vias not_allowed)
				(pads allowed)
				(copperpour not_allowed)
				(footprints allowed)
			)
			(placement
				(enabled no)
				(sheetname "")
			)
			(fill
				(thermal_gap 0.5)
				(thermal_bridge_width 0.5)
				(island_removal_mode 0)
			)
			(polygon
				(pts
					(xy 194.203828 -77.746352) (xy 194.711828 -77.746352) (xy 194.711828 -77.365352) (xy 194.203828 -77.365352)
				)
			)
		)
		(zone
			(layer "F.Cu")
			(hatch none 0.5)
			(connect_pads
				(clearance 0)
			)
			(min_thickness 0.25)
			(keepout
				(tracks not_allowed)
				(vias allowed)
				(pads allowed)
				(copperpour not_allowed)
				(footprints allowed)
			)
			(placement
				(enabled no)
				(sheetname "")
			)
			(fill
				(thermal_gap 0.5)
				(thermal_bridge_width 0.5)
				(island_removal_mode 0)
			)
			(polygon
				(pts
					(xy 194.203828 -77.365352) (xy 194.711828 -77.365352) (xy 194.711828 -77.746352) (xy 194.203828 -77.746352)
				)
			)
		)
	)
	(footprint ""
		(layer "F.Cu")
		(at 18.9484 -118.239794 90)
		(property "Reference" "R1B22"
			(at 0 0 90)
			(layer "F.SilkS")
			(hide yes)
			(effects
				(font
					(size 1.27 1.27)
				)
			)
		)
		(property "Value" ""
			(at 0 0 90)
			(layer "F.Fab")
			(effects
				(font
					(size 1.27 1.27)
				)
			)
		)
		(duplicate_pad_numbers_are_jumpers no)
		(fp_rect
			(start -0.2794 -0.1016)
			(end 0.2794 0.9906)
			(stroke
				(width 0)
				(type default)
			)
			(fill no)
			(layer "F.CrtYd")
		)
		(fp_line
			(start 0.2794 -0.1016)
			(end -0.2794 -0.1016)
			(stroke
				(width 0.1)
				(type default)
			)
			(layer "F.Fab")
		)
		(fp_line
			(start -0.2794 -0.1016)
			(end -0.2794 0.9906)
			(stroke
				(width 0.1)
				(type default)
			)
			(layer "F.Fab")
		)
		(fp_line
			(start 0.2794 0.9906)
			(end 0.2794 -0.1016)
			(stroke
				(width 0.1)
				(type default)
			)
			(layer "F.Fab")
		)
		(fp_line
			(start -0.2794 0.9906)
			(end 0.2794 0.9906)
			(stroke
				(width 0.1)
				(type default)
			)
			(layer "F.Fab")
		)
		(pad "1" smd rect
			(at 0 0 90)
			(size 0.508 0.508)
			(layers "F.Cu" "F.Mask" "F.Paste")
			(net "FAN_TACH2")
		)
		(pad "2" smd rect
			(at 0 0.889 90)
			(size 0.508 0.508)
			(layers "F.Cu" "F.Mask" "F.Paste")
			(net "FAN_TACH2_CPU1_D2")
		)
		(zone
			(layer "F.Cu")
			(hatch none 0.5)
			(connect_pads
				(clearance 0)
			)
			(min_thickness 0.25)
			(keepout
				(tracks allowed)
				(vias not_allowed)
				(pads allowed)
				(copperpour not_allowed)
				(footprints allowed)
			)
			(placement
				(enabled no)
				(sheetname "")
			)
			(fill
				(thermal_gap 0.5)
				(thermal_bridge_width 0.5)
				(island_removal_mode 0)
			)
			(polygon
				(pts
					(xy 19.2024 -117.985794) (xy 19.5834 -117.985794) (xy 19.5834 -118.493794) (xy 19.2024 -118.493794)
				)
			)
		)
		(zone
			(layer "F.Cu")
			(hatch none 0.5)
			(connect_pads
				(clearance 0)
			)
			(min_thickness 0.25)
			(keepout
				(tracks not_allowed)
				(vias allowed)
				(pads allowed)
				(copperpour not_allowed)
				(footprints allowed)
			)
			(placement
				(enabled no)
				(sheetname "")
			)
			(fill
				(thermal_gap 0.5)
				(thermal_bridge_width 0.5)
				(island_removal_mode 0)
			)
			(polygon
				(pts
					(xy 19.2024 -117.985794) (xy 19.5834 -117.985794) (xy 19.5834 -118.493794) (xy 19.2024 -118.493794)
				)
			)
		)
	)
	(footprint ""
		(layer "F.Cu")
		(at 485.875076 -26.326084 180)
		(property "Reference" "R9F70"
			(at 0 0 180)
			(layer "F.SilkS")
			(hide yes)
			(effects
				(font
					(size 1.27 1.27)
				)
			)
		)
		(property "Value" ""
			(at 0 0 180)
			(layer "F.Fab")
			(effects
				(font
					(size 1.27 1.27)
				)
			)
		)
		(duplicate_pad_numbers_are_jumpers no)
		(fp_poly
			(pts
				(xy -0.2794 -0.1016) (xy 0.2794 -0.1016) (xy 0.2794 0.9906) (xy -0.2794 0.9906)
			)
			(stroke
				(width 0)
				(type default)
			)
			(fill no)
			(layer "F.CrtYd")
		)
		(fp_line
			(start 0.2794 0.9906)
			(end 0.2794 -0.1016)
			(stroke
				(width 0.1)
				(type default)
			)
			(layer "F.Fab")
		)
		(fp_line
			(start 0.2794 -0.1016)
			(end -0.2794 -0.1016)
			(stroke
				(width 0.1)
				(type default)
			)
			(layer "F.Fab")
		)
		(fp_line
			(start -0.2794 0.9906)
			(end 0.2794 0.9906)
			(stroke
				(width 0.1)
				(type default)
			)
			(layer "F.Fab")
		)
		(fp_line
			(start -0.2794 -0.1016)
			(end -0.2794 0.9906)
			(stroke
				(width 0.1)
				(type default)
			)
			(layer "F.Fab")
		)
		(pad "1" smd rect
			(at 0 0 180)
			(size 0.508 0.508)
			(layers "F.Cu" "F.Mask" "F.Paste")
			(net "SPA_MID_DBG_TX")
		)
		(pad "2" smd rect
			(at 0 0.889 180)
			(size 0.508 0.508)
			(layers "F.Cu" "F.Mask" "F.Paste")
			(net "SPA_MID_DBG_TX_R")
		)
		(zone
			(layer "F.Cu")
			(hatch none 0.5)
			(connect_pads
				(clearance 0)
			)
			(min_thickness 0.25)
			(keepout
				(tracks not_allowed)
				(vias allowed)
				(pads allowed)
				(copperpour not_allowed)
				(footprints allowed)
			)
			(placement
				(enabled no)
				(sheetname "")
			)
			(fill
				(thermal_gap 0.5)
				(thermal_bridge_width 0.5)
				(island_removal_mode 0)
			)
			(polygon
				(pts
					(xy 486.129076 -26.961084) (xy 485.621076 -26.961084) (xy 485.621076 -26.580084) (xy 486.129076 -26.580084)
				)
			)
		)
		(zone
			(layer "F.Cu")
			(hatch none 0.5)
			(connect_pads
				(clearance 0)
			)
			(min_thickness 0.25)
			(keepout
				(tracks allowed)
				(vias not_allowed)
				(pads allowed)
				(copperpour not_allowed)
				(footprints allowed)
			)
			(placement
				(enabled no)
				(sheetname "")
			)
			(fill
				(thermal_gap 0.5)
				(thermal_bridge_width 0.5)
				(island_removal_mode 0)
			)
			(polygon
				(pts
					(xy 486.129076 -26.580084) (xy 485.621076 -26.580084) (xy 485.621076 -26.961084) (xy 486.129076 -26.961084)
				)
			)
		)
	)
)
